(kicad_pcb
	(version 20241229)
	(generator "pcbnew")
	(generator_version "9.0")
	(general
		(thickness 1.552)
		(legacy_teardrops no)
	)
	(paper "A4")
	(title_block
		(date "2023-07-25")
		(rev "1.1.4")
		(comment 9 "footprints 95-99 of 379")
	)
	(layers
		(0 "F.Cu" signal)
		(4 "In1.Cu" signal)
		(6 "In2.Cu" signal)
		(8 "In3.Cu" signal)
		(10 "In4.Cu" signal)
		(12 "In5.Cu" signal)
		(14 "In6.Cu" signal)
		(2 "B.Cu" signal)
		(9 "F.Adhes" user "F.Adhesive")
		(11 "B.Adhes" user "B.Adhesive")
		(13 "F.Paste" user)
		(15 "B.Paste" user)
		(5 "F.SilkS" user "F.Silkscreen")
		(7 "B.SilkS" user "B.Silkscreen")
		(1 "F.Mask" user)
		(3 "B.Mask" user)
		(17 "Dwgs.User" user "User.Drawings")
		(19 "Cmts.User" user "User.Comments")
		(21 "Eco1.User" user "User.Eco1")
		(23 "Eco2.User" user "User.Eco2")
		(25 "Edge.Cuts" user)
		(27 "Margin" user)
		(31 "F.CrtYd" user "F.Courtyard")
		(29 "B.CrtYd" user "B.Courtyard")
		(35 "F.Fab" user)
		(33 "B.Fab" user)
	)
	(footprint "antmicro-footprints:R_0402_1005Metric"
		(layer "F.Cu")
		(at 122.03 115.15)
		(descr "Resistor SMD 0402")
		(tags "resistor SMD 0402")
		(property "Reference" "R77"
			(at -3.9 0.29 0)
			(layer "F.SilkS")
			(effects
				(font
					(size 0.65 0.65)
					(thickness 0.15)
				)
				(justify left bottom)
			)
		)
		(property "Value" "R_0R_0402"
			(at 0 1.4 0)
			(layer "F.Fab")
			(hide yes)
			(effects
				(font
					(size 0.7 0.7)
					(thickness 0.15)
				)
				(justify left bottom)
			)
		)
		(property "Datasheet" "https://industrial.panasonic.com/cdbs/www-data/pdf/RDA0000/AOA0000C301.pdf"
			(at 0 0 0)
			(layer "F.Fab")
			(hide yes)
			(effects
				(font
					(size 1.27 1.27)
					(thickness 0.15)
				)
			)
		)
		(property "Description" "SMD Chip Resistor, Jumper, 0 ohm, 100 mW, 0402 [1005 Metric], Thick Film, General Purpose"
			(at 0 0 0)
			(layer "F.Fab")
			(hide yes)
			(effects
				(font
					(size 1.27 1.27)
					(thickness 0.15)
				)
			)
		)
		(property "Author" "Antmicro"
			(at 0 0 0)
			(layer "F.Fab")
			(hide yes)
			(effects
				(font
					(size 1 1)
					(thickness 0.15)
				)
			)
		)
		(property "Current" "1A"
			(at 0 0 0)
			(layer "F.Fab")
			(hide yes)
			(effects
				(font
					(size 1 1)
					(thickness 0.15)
				)
			)
		)
		(property "License" "Apache-2.0"
			(at 0 0 0)
			(layer "F.Fab")
			(hide yes)
			(effects
				(font
					(size 1 1)
					(thickness 0.15)
				)
			)
		)
		(property "MPN" "ERJ2GE0R00X"
			(at 0 0 0)
			(layer "F.Fab")
			(hide yes)
			(effects
				(font
					(size 1 1)
					(thickness 0.15)
				)
			)
		)
		(property "Manufacturer" "Panasonic"
			(at 0 0 0)
			(layer "F.Fab")
			(hide yes)
			(effects
				(font
					(size 1 1)
					(thickness 0.15)
				)
			)
		)
		(property "Tolerance" "~"
			(at 0 0 0)
			(layer "F.Fab")
			(hide yes)
			(effects
				(font
					(size 1 1)
					(thickness 0.15)
				)
			)
		)
		(property "Val" "0R"
			(at 0 0 0)
			(layer "F.Fab")
			(hide yes)
			(effects
				(font
					(size 1 1)
					(thickness 0.15)
				)
			)
		)
		(sheetname "/FPGA/")
		(sheetfile "fpga.kicad_sch")
		(attr smd)
		(fp_rect
			(start -0.925 -0.47)
			(end 0.925 0.47)
			(stroke
				(width 0.05)
				(type default)
			)
			(fill no)
			(layer "F.CrtYd")
		)
		(fp_rect
			(start -0.5 -0.25)
			(end 0.5 0.25)
			(stroke
				(width 0.15)
				(type solid)
			)
			(fill no)
			(layer "F.Fab")
		)
		(fp_text user "License: Apache-2.0"
			(at -0.95 5.169 0)
			(layer "F.Fab")
			(effects
				(font
					(size 0.7 0.7)
					(thickness 0.15)
				)
				(justify left bottom)
			)
		)
		(fp_text user "Author: Antmicro"
			(at -0.95 4.169 0)
			(layer "F.Fab")
			(effects
				(font
					(size 0.7 0.7)
					(thickness 0.15)
				)
				(justify left bottom)
			)
		)
		(fp_text user "${REFERENCE}"
			(at -0.95 3.168 0)
			(layer "F.Fab")
			(effects
				(font
					(size 0.7 0.7)
					(thickness 0.15)
				)
				(justify left bottom)
			)
		)
		(pad "1" smd roundrect
			(at -0.48 0)
			(size 0.59 0.64)
			(layers "F.Cu" "F.Mask" "F.Paste")
			(roundrect_rratio 0.25)
			(net 40 "/FPGA/DONE")
			(pintype "passive")
		)
		(pad "2" smd roundrect
			(at 0.48 0)
			(size 0.59 0.64)
			(layers "F.Cu" "F.Mask" "F.Paste")
			(roundrect_rratio 0.25)
			(net 363 "/FPGA/DONE_SOFT")
			(pintype "passive")
		)
	)
	(footprint "antmicro-footprints:R_0402_1005Metric"
		(layer "F.Cu")
		(at 144.49 111.2 90)
		(descr "Resistor SMD 0402")
		(tags "resistor SMD 0402")
		(property "Reference" "R28"
			(at 0.86 0.34 90)
			(layer "F.SilkS")
			(effects
				(font
					(size 0.65 0.65)
					(thickness 0.15)
				)
				(justify left bottom)
			)
		)
		(property "Value" "R_0R_0402"
			(at 0 1.4 90)
			(layer "F.Fab")
			(hide yes)
			(effects
				(font
					(size 0.7 0.7)
					(thickness 0.15)
				)
				(justify left bottom)
			)
		)
		(property "Datasheet" "https://industrial.panasonic.com/cdbs/www-data/pdf/RDA0000/AOA0000C301.pdf"
			(at 0 0 90)
			(layer "F.Fab")
			(hide yes)
			(effects
				(font
					(size 1.27 1.27)
					(thickness 0.15)
				)
			)
		)
		(property "Description" "SMD Chip Resistor, Jumper, 0 ohm, 100 mW, 0402 [1005 Metric], Thick Film, General Purpose"
			(at 0 0 90)
			(layer "F.Fab")
			(hide yes)
			(effects
				(font
					(size 1.27 1.27)
					(thickness 0.15)
				)
			)
		)
		(property "Author" "Antmicro"
			(at 255.69 -33.29 0)
			(layer "F.Fab")
			(hide yes)
			(effects
				(font
					(size 1 1)
					(thickness 0.15)
				)
			)
		)
		(property "Current" "1A"
			(at 255.69 -33.29 0)
			(layer "F.Fab")
			(hide yes)
			(effects
				(font
					(size 1 1)
					(thickness 0.15)
				)
			)
		)
		(property "License" "Apache-2.0"
			(at 255.69 -33.29 0)
			(layer "F.Fab")
			(hide yes)
			(effects
				(font
					(size 1 1)
					(thickness 0.15)
				)
			)
		)
		(property "MPN" "ERJ2GE0R00X"
			(at 255.69 -33.29 0)
			(layer "F.Fab")
			(hide yes)
			(effects
				(font
					(size 1 1)
					(thickness 0.15)
				)
			)
		)
		(property "Manufacturer" "Panasonic"
			(at 255.69 -33.29 0)
			(layer "F.Fab")
			(hide yes)
			(effects
				(font
					(size 1 1)
					(thickness 0.15)
				)
			)
		)
		(property "Tolerance" "~"
			(at 255.69 -33.29 0)
			(layer "F.Fab")
			(hide yes)
			(effects
				(font
					(size 1 1)
					(thickness 0.15)
				)
			)
		)
		(property "Val" "0R"
			(at 255.69 -33.29 0)
			(layer "F.Fab")
			(hide yes)
			(effects
				(font
					(size 1 1)
					(thickness 0.15)
				)
			)
		)
		(sheetname "/Power Supply/")
		(sheetfile "supply.kicad_sch")
		(attr smd)
		(fp_rect
			(start -0.925 -0.47)
			(end 0.925 0.47)
			(stroke
				(width 0.05)
				(type default)
			)
			(fill no)
			(layer "F.CrtYd")
		)
		(fp_rect
			(start -0.5 -0.25)
			(end 0.5 0.25)
			(stroke
				(width 0.15)
				(type solid)
			)
			(fill no)
			(layer "F.Fab")
		)
		(fp_text user "${REFERENCE}"
			(at -0.95 3.168 90)
			(layer "F.Fab")
			(effects
				(font
					(size 0.7 0.7)
					(thickness 0.15)
				)
				(justify left bottom)
			)
		)
		(fp_text user "Author: Antmicro"
			(at -0.95 4.169 90)
			(layer "F.Fab")
			(effects
				(font
					(size 0.7 0.7)
					(thickness 0.15)
				)
				(justify left bottom)
			)
		)
		(fp_text user "License: Apache-2.0"
			(at -0.95 5.169 90)
			(layer "F.Fab")
			(effects
				(font
					(size 0.7 0.7)
					(thickness 0.15)
				)
				(justify left bottom)
			)
		)
		(pad "1" smd roundrect
			(at -0.48 0 90)
			(size 0.59 0.64)
			(layers "F.Cu" "F.Mask" "F.Paste")
			(roundrect_rratio 0.25)
			(net 266 "Net-(U10-V_{IN})")
			(pintype "passive")
		)
		(pad "2" smd roundrect
			(at 0.48 0 90)
			(size 0.59 0.64)
			(layers "F.Cu" "F.Mask" "F.Paste")
			(roundrect_rratio 0.25)
			(net 271 "Net-(U10-EN)")
			(pintype "passive")
		)
	)
	(footprint "antmicro-footprints:LED_0603_1608Metric_G"
		(layer "F.Cu")
		(at 108.75 73.4 90)
		(descr "LED SMD 0603 Green")
		(tags "LED SMD 0603 Green")
		(property "Reference" "D8"
			(at -2.94 -0.32 90)
			(layer "F.SilkS")
			(effects
				(font
					(size 0.65 0.65)
					(thickness 0.15)
				)
				(justify left top)
			)
		)
		(property "Value" "LED_G_0603_LTST-C190GKT"
			(at 0 1.6 90)
			(layer "F.Fab")
			(hide yes)
			(effects
				(font
					(size 0.7 0.7)
					(thickness 0.15)
				)
				(justify left top)
			)
		)
		(property "Datasheet" "https://media.digikey.com/pdf/Data%20Sheets/Lite-On%20PDFs/LTST-C190GKT.pdf"
			(at 0 0 90)
			(layer "F.Fab")
			(hide yes)
			(effects
				(font
					(size 1.27 1.27)
					(thickness 0.15)
				)
			)
		)
		(property "Description" "LED, Green, SMD, 0603, 20 mA, 2.1 V, 569 nm"
			(at 0 0 90)
			(layer "F.Fab")
			(hide yes)
			(effects
				(font
					(size 1.27 1.27)
					(thickness 0.15)
				)
			)
		)
		(property "Author" "Antmicro"
			(at 35.35 182.15 0)
			(layer "F.Fab")
			(hide yes)
			(effects
				(font
					(size 1 1)
					(thickness 0.15)
				)
			)
		)
		(property "License" "Apache-2.0"
			(at 35.35 182.15 0)
			(layer "F.Fab")
			(hide yes)
			(effects
				(font
					(size 1 1)
					(thickness 0.15)
				)
			)
		)
		(property "MPN" "LTST-C190GKT"
			(at 35.35 182.15 0)
			(layer "F.Fab")
			(hide yes)
			(effects
				(font
					(size 1 1)
					(thickness 0.15)
				)
			)
		)
		(property "Manufacturer" "Lite-On"
			(at 35.35 182.15 0)
			(layer "F.Fab")
			(hide yes)
			(effects
				(font
					(size 1 1)
					(thickness 0.15)
				)
			)
		)
		(property "Color" "Green"
			(at 0 0 90)
			(unlocked yes)
			(layer "F.Fab")
			(hide yes)
			(effects
				(font
					(size 1 1)
					(thickness 0.15)
				)
			)
		)
		(sheetname "/SDI/")
		(sheetfile "sdi.kicad_sch")
		(attr smd)
		(fp_line
			(start 0.22 -0.35)
			(end -0.22 -0.35)
			(stroke
				(width 0.15)
				(type solid)
			)
			(layer "F.SilkS")
		)
		(fp_line
			(start -1.18 -0.319)
			(end -1.18 0.321)
			(stroke
				(width 0.15)
				(type solid)
			)
			(layer "F.SilkS")
		)
		(fp_line
			(start 0.105328 0.001008)
			(end 0.24 0.001)
			(stroke
				(width 0.1)
				(type solid)
			)
			(layer "F.SilkS")
		)
		(fp_line
			(start -0.094672 0.001008)
			(end 0.105328 -0.198992)
			(stroke
				(width 0.1)
				(type solid)
			)
			(layer "F.SilkS")
		)
		(fp_line
			(start -0.094672 0.001008)
			(end -0.24 0.001008)
			(stroke
				(width 0.1)
				(type solid)
			)
			(layer "F.SilkS")
		)
		(fp_line
			(start 0.105328 0.201008)
			(end 0.105328 -0.198992)
			(stroke
				(width 0.1)
				(type solid)
			)
			(layer "F.SilkS")
		)
		(fp_line
			(start 0.105328 0.201008)
			(end -0.094672 0.001008)
			(stroke
				(width 0.1)
				(type solid)
			)
			(layer "F.SilkS")
		)
		(fp_line
			(start -0.094672 0.201008)
			(end -0.094672 -0.198992)
			(stroke
				(width 0.1)
				(type solid)
			)
			(layer "F.SilkS")
		)
		(fp_line
			(start 0.22 0.35)
			(end -0.22 0.35)
			(stroke
				(width 0.15)
				(type solid)
			)
			(layer "F.SilkS")
		)
		(fp_rect
			(start 1.25 0.65)
			(end -1.25 -0.65)
			(stroke
				(width 0.05)
				(type solid)
			)
			(fill no)
			(layer "F.CrtYd")
		)
		(fp_line
			(start 0.201 -0.202)
			(end -0.101 0)
			(stroke
				(width 0.15)
				(type solid)
			)
			(layer "F.Fab")
		)
		(fp_line
			(start -0.199 -0.202)
			(end -0.199 0.1)
			(stroke
				(width 0.15)
				(type solid)
			)
			(layer "F.Fab")
		)
		(fp_line
			(start 0.599 0)
			(end 0.201 0)
			(stroke
				(width 0.15)
				(type solid)
			)
			(layer "F.Fab")
		)
		(fp_line
			(start 0.201 0)
			(end 0.201 -0.202)
			(stroke
				(width 0.15)
				(type solid)
			)
			(layer "F.Fab")
		)
		(fp_line
			(start -0.101 0)
			(end 0.201 0.2)
			(stroke
				(width 0.15)
				(type solid)
			)
			(layer "F.Fab")
		)
		(fp_line
			(start -0.199 0)
			(end -0.597 0)
			(stroke
				(width 0.15)
				(type solid)
			)
			(layer "F.Fab")
		)
		(fp_line
			(start 0.201 0.2)
			(end 0.201 0)
			(stroke
				(width 0.15)
				(type solid)
			)
			(layer "F.Fab")
		)
		(fp_line
			(start -0.199 0.2)
			(end -0.199 0.1)
			(stroke
				(width 0.15)
				(type solid)
			)
			(layer "F.Fab")
		)
		(fp_rect
			(start 0.848 0.4)
			(end -0.85 -0.402)
			(stroke
				(width 0.15)
				(type solid)
			)
			(fill no)
			(layer "F.Fab")
		)
		(fp_text user "License: Apache-2.0"
			(at -1.4224 3.599 90)
			(layer "F.Fab")
			(effects
				(font
					(size 0.7 0.7)
					(thickness 0.15)
				)
				(justify left bottom)
			)
		)
		(fp_text user "Author: Antmicro"
			(at -1.4224 4.799 90)
			(layer "F.Fab")
			(effects
				(font
					(size 0.7 0.7)
					(thickness 0.15)
				)
				(justify left bottom)
			)
		)
		(fp_text user "${REFERENCE}"
			(at -1.4224 5.999 90)
			(layer "F.Fab")
			(effects
				(font
					(size 0.7 0.7)
					(thickness 0.15)
				)
				(justify left bottom)
			)
		)
		(pad "1" smd roundrect
			(at -0.7 0 270)
			(size 0.8 1)
			(layers "F.Cu" "F.Mask" "F.Paste")
			(roundrect_rratio 0.2)
			(net 1 "GND")
			(pinfunction "C")
			(pintype "passive")
		)
		(pad "2" smd roundrect
			(at 0.7 0 270)
			(size 0.8 1)
			(layers "F.Cu" "F.Mask" "F.Paste")
			(roundrect_rratio 0.2)
			(net 247 "Net-(D8-A)")
			(pinfunction "A")
			(pintype "passive")
		)
	)
	(footprint "antmicro-footprints:R_0402_1005Metric"
		(layer "F.Cu")
		(at 86.6 75.4)
		(descr "Resistor SMD 0402")
		(tags "resistor SMD 0402")
		(property "Reference" "R51"
			(at -2.77 -6.26 0)
			(layer "F.SilkS")
			(effects
				(font
					(size 0.65 0.65)
					(thickness 0.15)
				)
				(justify left bottom)
			)
		)
		(property "Value" "R_75R_0402"
			(at 0 1.4 0)
			(layer "F.Fab")
			(hide yes)
			(effects
				(font
					(size 0.7 0.7)
					(thickness 0.15)
				)
				(justify left bottom)
			)
		)
		(property "Datasheet" "https://www.bourns.com/docs/product-datasheets/cr.pdf"
			(at 0 0 0)
			(layer "F.Fab")
			(hide yes)
			(effects
				(font
					(size 1.27 1.27)
					(thickness 0.15)
				)
			)
		)
		(property "Description" "SMD Chip Resistor, 75 ohm, ± 1%, 62.5 mW, 0402 [1005 Metric], Thick Film, General Purpose"
			(at 0 0 0)
			(layer "F.Fab")
			(hide yes)
			(effects
				(font
					(size 1.27 1.27)
					(thickness 0.15)
				)
			)
		)
		(property "Author" "Antmicro"
			(at 0 0 0)
			(layer "F.Fab")
			(hide yes)
			(effects
				(font
					(size 1 1)
					(thickness 0.15)
				)
			)
		)
		(property "License" "Apache-2.0"
			(at 0 0 0)
			(layer "F.Fab")
			(hide yes)
			(effects
				(font
					(size 1 1)
					(thickness 0.15)
				)
			)
		)
		(property "MPN" "CR0402-FX-75R0GLF"
			(at 0 0 0)
			(layer "F.Fab")
			(hide yes)
			(effects
				(font
					(size 1 1)
					(thickness 0.15)
				)
			)
		)
		(property "Manufacturer" "Bourns"
			(at 0 0 0)
			(layer "F.Fab")
			(hide yes)
			(effects
				(font
					(size 1 1)
					(thickness 0.15)
				)
			)
		)
		(property "Tolerance" "1%"
			(at 0 0 0)
			(layer "F.Fab")
			(hide yes)
			(effects
				(font
					(size 1 1)
					(thickness 0.15)
				)
			)
		)
		(property "Val" "75R"
			(at 0 0 0)
			(layer "F.Fab")
			(hide yes)
			(effects
				(font
					(size 1 1)
					(thickness 0.15)
				)
			)
		)
		(sheetname "/SDI/")
		(sheetfile "sdi.kicad_sch")
		(attr smd)
		(fp_rect
			(start -0.925 -0.47)
			(end 0.925 0.47)
			(stroke
				(width 0.05)
				(type default)
			)
			(fill no)
			(layer "F.CrtYd")
		)
		(fp_rect
			(start -0.5 -0.25)
			(end 0.5 0.25)
			(stroke
				(width 0.15)
				(type solid)
			)
			(fill no)
			(layer "F.Fab")
		)
		(fp_text user "Author: Antmicro"
			(at -0.95 4.169 0)
			(layer "F.Fab")
			(effects
				(font
					(size 0.7 0.7)
					(thickness 0.15)
				)
				(justify left bottom)
			)
		)
		(fp_text user "License: Apache-2.0"
			(at -0.95 5.169 0)
			(layer "F.Fab")
			(effects
				(font
					(size 0.7 0.7)
					(thickness 0.15)
				)
				(justify left bottom)
			)
		)
		(fp_text user "${REFERENCE}"
			(at -0.95 3.168 0)
			(layer "F.Fab")
			(effects
				(font
					(size 0.7 0.7)
					(thickness 0.15)
				)
				(justify left bottom)
			)
		)
		(pad "1" smd roundrect
			(at -0.48 0)
			(size 0.59 0.64)
			(layers "F.Cu" "F.Mask" "F.Paste")
			(roundrect_rratio 0.25)
			(net 253 "/SDI/SDI_IN")
			(pintype "passive")
		)
		(pad "2" smd roundrect
			(at 0.48 0)
			(size 0.59 0.64)
			(layers "F.Cu" "F.Mask" "F.Paste")
			(roundrect_rratio 0.25)
			(net 243 "/SDI/SDI_IN_F")
			(pintype "passive")
		)
	)
	(footprint "antmicro-footprints:R_0805_2012Metric"
		(layer "F.Cu")
		(at 146.98 67.85 180)
		(property "Reference" "R15"
			(at -0.95 1.01 0)
			(layer "F.SilkS")
			(effects
				(font
					(size 0.65 0.65)
					(thickness 0.15)
				)
				(justify right bottom)
			)
		)
		(property "Value" "R_0R_0805"
			(at 0 1.8 0)
			(layer "F.Fab")
			(hide yes)
			(effects
				(font
					(size 0.7 0.7)
					(thickness 0.15)
				)
				(justify right bottom)
			)
		)
		(property "Datasheet" "https://www.vishay.com/docs/20035/dcrcwe3.pdf"
			(at 0 0 180)
			(layer "F.Fab")
			(hide yes)
			(effects
				(font
					(size 1.27 1.27)
					(thickness 0.15)
				)
			)
		)
		(property "Description" "Zero Ohm Resistor, Jumper, 0805 [2012 Metric], Thick Film, 125 mW, 2.5 A, Surface Mount Device"
			(at 0 0 180)
			(layer "F.Fab")
			(hide yes)
			(effects
				(font
					(size 1.27 1.27)
					(thickness 0.15)
				)
			)
		)
		(property "Author" "Antmicro"
			(at 293.96 135.7 0)
			(layer "F.Fab")
			(hide yes)
			(effects
				(font
					(size 1 1)
					(thickness 0.15)
				)
			)
		)
		(property "Current" "2.5A"
			(at 293.96 135.7 0)
			(layer "F.Fab")
			(hide yes)
			(effects
				(font
					(size 1 1)
					(thickness 0.15)
				)
			)
		)
		(property "License" "Apache-2.0"
			(at 293.96 135.7 0)
			(layer "F.Fab")
			(hide yes)
			(effects
				(font
					(size 1 1)
					(thickness 0.15)
				)
			)
		)
		(property "MPN" "CRCW08050000Z0EA"
			(at 293.96 135.7 0)
			(layer "F.Fab")
			(hide yes)
			(effects
				(font
					(size 1 1)
					(thickness 0.15)
				)
			)
		)
		(property "Manufacturer" "Vishay"
			(at 293.96 135.7 0)
			(layer "F.Fab")
			(hide yes)
			(effects
				(font
					(size 1 1)
					(thickness 0.15)
				)
			)
		)
		(property "Tolerance" "~"
			(at 293.96 135.7 0)
			(layer "F.Fab")
			(hide yes)
			(effects
				(font
					(size 1 1)
					(thickness 0.15)
				)
			)
		)
		(property "Val" "0R"
			(at 293.96 135.7 0)
			(layer "F.Fab")
			(hide yes)
			(effects
				(font
					(size 1 1)
					(thickness 0.15)
				)
			)
		)
		(sheetname "/Power Supply/")
		(sheetfile "supply.kicad_sch")
		(attr smd)
		(fp_line
			(start -0.3 -0.701)
			(end 0.298 -0.701)
			(stroke
				(width 0.15)
				(type solid)
			)
			(layer "F.SilkS")
		)
		(fp_line
			(start -0.32 0.699)
			(end 0.28 0.699)
			(stroke
				(width 0.15)
				(type solid)
			)
			(layer "F.SilkS")
		)
		(fp_rect
			(start 1.95 -0.9)
			(end -1.95 0.9)
			(stroke
				(width 0.05)
				(type default)
			)
			(fill no)
			(layer "F.CrtYd")
		)
		(fp_line
			(start 0.949 -0.677)
			(end 0.949 0.675)
			(stroke
				(width 0.15)
				(type solid)
			)
			(layer "F.Fab")
		)
		(fp_line
			(start -0.951 0.68)
			(end 0.949 0.68)
			(stroke
				(width 0.15)
				(type solid)
			)
			(layer "F.Fab")
		)
		(fp_line
			(start -0.951 -0.677)
			(end -0.951 0.675)
			(stroke
				(width 0.15)
				(type solid)
			)
			(layer "F.Fab")
		)
		(fp_line
			(start -0.951 -0.682)
			(end 0.949 -0.682)
			(stroke
				(width 0.15)
				(type solid)
			)
			(layer "F.Fab")
		)
		(fp_text user "${REFERENCE}"
			(at -1.9 3.1 180)
			(layer "F.Fab")
			(effects
				(font
					(size 0.7 0.7)
					(thickness 0.15)
				)
				(justify left bottom)
			)
		)
		(fp_text user "License: Apache-2.0"
			(at -1.9 5.75 180)
			(layer "F.Fab")
			(effects
				(font
					(size 0.7 0.7)
					(thickness 0.15)
				)
				(justify left bottom)
			)
		)
		(fp_text user "Author: Antmicro"
			(at -1.9 4.4 180)
			(layer "F.Fab")
			(effects
				(font
					(size 0.7 0.7)
					(thickness 0.15)
				)
				(justify left bottom)
			)
		)
		(pad "1" smd roundrect
			(at -1.1 0 180)
			(size 1.2 1.3)
			(layers "F.Cu" "F.Mask" "F.Paste")
			(roundrect_rratio 0.25)
			(net 14 "+5V")
			(pintype "passive")
		)
		(pad "2" smd roundrect
			(at 1.1 0 180)
			(size 1.2 1.3)
			(layers "F.Cu" "F.Mask" "F.Paste")
			(roundrect_rratio 0.25)
			(net 326 "/Power Supply/5V_1V0_IN")
			(pintype "passive")
		)
	)
)
